# T6G (Grand Teton) — schematic netlist excerpt (pin names and nets, part order shuffled) for the footprints in the layout excerpt that follows; sources: Cadence DE-HDL packaged netlist, KiCad conversion of 04192023_DAF0TMB3IC0_F0TG_MB_C_brd_V02_OCP.brd

C6595  Q_CAP_DIFFBUS  DIFF BUS_0.22UF 6.3V 20% X6S  pkg C0201  page 297 : \1\ = P5E_CPU0_P2_TX_BUF_C_DP<15> ; \2\ = P5E_CPU0_P2_TX_BUF_DP<15>
PC228  Q_CAPP  390UF 2.5V 20% ALUM  pkg SMLF  page 208 : A = PVDD11_S3_P0 ; B = GND
PC322_SOP1_2  Q_CAP  2.2UF 10V 10% X6S  pkg C0402  page 215 : A = PVDDCR_CPU0_P1_PVCC ; B = GND

(kicad_pcb
	(version 20260206)
	(generator "pcbnew")
	(generator_version "10.0")
	(general
		(thickness 1.6)
		(legacy_teardrops no)
	)
	(paper "A4")
	(title_block
		(title "04192023_DAF0TMB3IC0_F0TG_MB_C_brd_V02_OCP.brd")
		(comment 1 "Grand Teton / footprints 1475-1477 of 8354")
	)
	(layers
		(0 "F.Cu" signal "TOP")
		(4 "In1.Cu" signal "GND")
		(6 "In2.Cu" signal "IN1")
		(8 "In3.Cu" signal "GND1")
		(10 "In4.Cu" signal "IN2")
		(12 "In5.Cu" signal "GND2")
		(14 "In6.Cu" signal "IN3")
		(16 "In7.Cu" signal "GND3")
		(18 "In8.Cu" signal "VCC")
		(20 "In9.Cu" signal "VCC1")
		(22 "In10.Cu" signal "GND4")
		(24 "In11.Cu" signal "IN4")
		(26 "In12.Cu" signal "GND5")
		(28 "In13.Cu" signal "IN5")
		(30 "In14.Cu" signal "GND6")
		(32 "In15.Cu" signal "IN6")
		(34 "In16.Cu" signal "GND7")
		(2 "B.Cu" signal "BOTTOM")
		(9 "F.Adhes" user "F.Adhesive")
		(11 "B.Adhes" user "B.Adhesive")
		(13 "F.Paste" user "Package Geometry/Pastemask Top")
		(15 "B.Paste" user "Package Geometry/Pastemask Bottom")
		(5 "F.SilkS" user "Ref Des/Silkscreen Top")
		(7 "B.SilkS" user "Ref Des/Silkscreen Bottom")
		(1 "F.Mask" user "Board Geometry/Soldermask Top")
		(3 "B.Mask" user "Board Geometry/Soldermask Bottom")
		(17 "Dwgs.User" user "User.Drawings")
		(19 "Cmts.User" user "User.Comments")
		(21 "Eco1.User" user "User.Eco1")
		(23 "Eco2.User" user "User.Eco2")
		(25 "Edge.Cuts" user "Board Geometry/Outline")
		(27 "Margin" user)
		(31 "F.CrtYd" user "Package Geometry/Place Bound Top")
		(29 "B.CrtYd" user "Package Geometry/Place Bound Bottom")
		(35 "F.Fab" user "Ref Des/Assembly Top")
		(33 "B.Fab" user "Ref Des/Assembly Bottom")
	)
	(footprint ""
		(layer "F.Cu")
		(at 127.64897 -165.194234 90)
		(property "Reference" "PC322_SOP1_2"
			(at 0 0 90)
			(layer "F.SilkS")
			(hide yes)
			(effects
				(font
					(size 1.27 1.27)
				)
			)
		)
		(property "Value" ""
			(at 0 0 90)
			(layer "F.Fab")
			(effects
				(font
					(size 1.27 1.27)
				)
			)
		)
		(duplicate_pad_numbers_are_jumpers no)
		(fp_line
			(start 0.7874 -0.4064)
			(end 0.7874 0.4064)
			(stroke
				(width 0.1524)
				(type default)
			)
			(layer "F.SilkS")
		)
		(fp_line
			(start -0.7874 -0.4064)
			(end 0.7874 -0.4064)
			(stroke
				(width 0.1524)
				(type default)
			)
			(layer "F.SilkS")
		)
		(fp_line
			(start 0.7874 0.4064)
			(end -0.7874 0.4064)
			(stroke
				(width 0.1524)
				(type default)
			)
			(layer "F.SilkS")
		)
		(fp_line
			(start -0.7874 0.4064)
			(end -0.7874 -0.4064)
			(stroke
				(width 0.1524)
				(type default)
			)
			(layer "F.SilkS")
		)
		(fp_line
			(start -0.12065 -0.305054)
			(end -0.12065 -0.2794)
			(stroke
				(width 0.1)
				(type default)
			)
			(layer "F.Fab")
		)
		(fp_line
			(start -0.67945 -0.305054)
			(end -0.12065 -0.305054)
			(stroke
				(width 0.1)
				(type default)
			)
			(layer "F.Fab")
		)
		(fp_line
			(start 0.67945 -0.3048)
			(end 0.67945 0.3048)
			(stroke
				(width 0.1)
				(type default)
			)
			(layer "F.Fab")
		)
		(fp_line
			(start 0.12065 -0.3048)
			(end 0.67945 -0.3048)
			(stroke
				(width 0.1)
				(type default)
			)
			(layer "F.Fab")
		)
		(fp_line
			(start 0.12065 -0.2794)
			(end 0.12065 -0.3048)
			(stroke
				(width 0.1)
				(type default)
			)
			(layer "F.Fab")
		)
		(fp_line
			(start -0.12065 -0.2794)
			(end 0.12065 -0.2794)
			(stroke
				(width 0.1)
				(type default)
			)
			(layer "F.Fab")
		)
		(fp_line
			(start 0.120396 0.2794)
			(end -0.12065 0.2794)
			(stroke
				(width 0.1)
				(type default)
			)
			(layer "F.Fab")
		)
		(fp_line
			(start -0.12065 0.2794)
			(end -0.12065 0.3048)
			(stroke
				(width 0.1)
				(type default)
			)
			(layer "F.Fab")
		)
		(fp_line
			(start 0.67945 0.3048)
			(end 0.120396 0.3048)
			(stroke
				(width 0.1)
				(type default)
			)
			(layer "F.Fab")
		)
		(fp_line
			(start 0.120396 0.3048)
			(end 0.120396 0.2794)
			(stroke
				(width 0.1)
				(type default)
			)
			(layer "F.Fab")
		)
		(fp_line
			(start -0.12065 0.3048)
			(end -0.67945 0.3048)
			(stroke
				(width 0.1)
				(type default)
			)
			(layer "F.Fab")
		)
		(fp_line
			(start -0.67945 0.3048)
			(end -0.67945 -0.305054)
			(stroke
				(width 0.1)
				(type default)
			)
			(layer "F.Fab")
		)
		(pad "1" smd circle
			(at -0.40005 0 90)
			(size 0 0)
			(layers "F.Cu" "F.Mask" "F.Paste")
			(net "PVDDCR_CPU0_P1_PVCC")
		)
		(pad "2" smd circle
			(at 0.40005 0 90)
			(size 0 0)
			(layers "F.Cu" "F.Mask" "F.Paste")
			(net "GND")
		)
	)
	(footprint ""
		(layer "F.Cu")
		(at 417.731702 -416.899344 -90)
		(property "Reference" "C6595"
			(at 0 0 270)
			(layer "F.SilkS")
			(hide yes)
			(effects
				(font
					(size 1.27 1.27)
				)
			)
		)
		(property "Value" ""
			(at 0 0 270)
			(layer "F.Fab")
			(effects
				(font
					(size 1.27 1.27)
				)
			)
		)
		(duplicate_pad_numbers_are_jumpers no)
		(fp_line
			(start -0.299974 0.150114)
			(end -0.299974 -0.150114)
			(stroke
				(width 0.1)
				(type default)
			)
			(layer "F.Fab")
		)
		(fp_line
			(start 0.299974 0.150114)
			(end -0.299974 0.150114)
			(stroke
				(width 0.1)
				(type default)
			)
			(layer "F.Fab")
		)
		(fp_line
			(start -0.299974 -0.150114)
			(end 0.299974 -0.150114)
			(stroke
				(width 0.1)
				(type default)
			)
			(layer "F.Fab")
		)
		(fp_line
			(start 0.299974 -0.150114)
			(end 0.299974 0.150114)
			(stroke
				(width 0.1)
				(type default)
			)
			(layer "F.Fab")
		)
		(pad "1" smd rect
			(at -0.2667 0 270)
			(size 0.3048 0.381)
			(layers "F.Cu" "F.Mask" "F.Paste")
			(net "P5E_CPU0_P2_TX_BUF_C_DP<15>")
		)
		(pad "2" smd rect
			(at 0.2667 0 270)
			(size 0.3048 0.381)
			(layers "F.Cu" "F.Mask" "F.Paste")
			(net "P5E_CPU0_P2_TX_BUF_DP<15>")
		)
	)
	(footprint ""
		(layer "F.Cu")
		(at 420.591488 -332.63586 -90)
		(property "Reference" "PC228"
			(at -4.97332 -17.659096 90)
			(unlocked yes)
			(layer "F.SilkS")
			(effects
				(font
					(size 0.7874 0.5842)
					(thickness 0.1524)
				)
				(justify left)
			)
		)
		(property "Value" ""
			(at 0 0 270)
			(layer "F.Fab")
			(effects
				(font
					(size 1.27 1.27)
				)
			)
		)
		(duplicate_pad_numbers_are_jumpers no)
		(fp_line
			(start -1.988058 2.750058)
			(end 2.750058 2.750058)
			(stroke
				(width 0.1524)
				(type default)
			)
			(layer "F.SilkS")
		)
		(fp_line
			(start 2.750058 2.750058)
			(end 2.750058 0.9398)
			(stroke
				(width 0.1524)
				(type default)
			)
			(layer "F.SilkS")
		)
		(fp_line
			(start -2.750058 1.988058)
			(end -1.988058 2.750058)
			(stroke
				(width 0.1524)
				(type default)
			)
			(layer "F.SilkS")
		)
		(fp_line
			(start -2.750058 0.9398)
			(end -2.750058 1.988058)
			(stroke
				(width 0.1524)
				(type default)
			)
			(layer "F.SilkS")
		)
		(fp_line
			(start 2.750058 -0.9398)
			(end 2.750058 -2.750058)
			(stroke
				(width 0.1524)
				(type default)
			)
			(layer "F.SilkS")
		)
		(fp_line
			(start -2.750058 -1.988058)
			(end -2.750058 -0.9398)
			(stroke
				(width 0.1524)
				(type default)
			)
			(layer "F.SilkS")
		)
		(fp_line
			(start -1.988058 -2.750058)
			(end -2.750058 -1.988058)
			(stroke
				(width 0.1524)
				(type default)
			)
			(layer "F.SilkS")
		)
		(fp_line
			(start 2.750058 -2.750058)
			(end -1.988058 -2.750058)
			(stroke
				(width 0.1524)
				(type default)
			)
			(layer "F.SilkS")
		)
		(fp_line
			(start -2.750058 2.750058)
			(end 2.750058 2.750058)
			(stroke
				(width 0.1)
				(type default)
			)
			(layer "F.Fab")
		)
		(fp_line
			(start 2.750058 2.750058)
			(end 2.750058 -2.750058)
			(stroke
				(width 0.1)
				(type default)
			)
			(layer "F.Fab")
		)
		(fp_line
			(start -2.750058 -2.750058)
			(end -2.750058 2.750058)
			(stroke
				(width 0.1)
				(type default)
			)
			(layer "F.Fab")
		)
		(fp_line
			(start 2.750058 -2.750058)
			(end -2.750058 -2.750058)
			(stroke
				(width 0.1)
				(type default)
			)
			(layer "F.Fab")
		)
		(pad "1" smd rect
			(at -2.199894 0)
			(size 1.6002 3.0226)
			(layers "F.Cu" "F.Mask" "F.Paste")
			(net "PVDD11_S3_P0")
		)
		(pad "2" smd rect
			(at 2.199894 0)
			(size 1.6002 3.0226)
			(layers "F.Cu" "F.Mask" "F.Paste")
			(net "GND")
		)
	)
)
